(kicad_pcb
	(version 20260206)
	(generator "pcbnew")
	(generator_version "10.0")
	(general
		(thickness 1.6)
		(legacy_teardrops no)
	)
	(paper "A4")
	(title_block
		(title "Bryce Canyon_SCC_16316-1_OCP.brd")
		(comment 1 "Bryce Canyon / footprint 257 of 1561 (CN6), pads 1-75 of 76")
	)
	(layers
		(0 "F.Cu" signal "TOP")
		(4 "In1.Cu" signal "L2GND")
		(6 "In2.Cu" signal "L3")
		(8 "In3.Cu" signal "L4VCC")
		(10 "In4.Cu" signal "L5VCC")
		(12 "In5.Cu" signal "L6")
		(14 "In6.Cu" signal "L7GND")
		(2 "B.Cu" signal "BOTTOM")
		(9 "F.Adhes" user "F.Adhesive")
		(11 "B.Adhes" user "B.Adhesive")
		(13 "F.Paste" user "Package Geometry/Pastemask Top")
		(15 "B.Paste" user "Package Geometry/Pastemask Bottom")
		(5 "F.SilkS" user "Ref Des/Silkscreen Top")
		(7 "B.SilkS" user "Ref Des/Silkscreen Bottom")
		(1 "F.Mask" user "Board Geometry/Soldermask Top")
		(3 "B.Mask" user "Board Geometry/Soldermask Bottom")
		(17 "Dwgs.User" user "User.Drawings")
		(19 "Cmts.User" user "User.Comments")
		(21 "Eco1.User" user "User.Eco1")
		(23 "Eco2.User" user "User.Eco2")
		(25 "Edge.Cuts" user "Board Geometry/Outline")
		(27 "Margin" user)
		(31 "F.CrtYd" user "Package Geometry/Place Bound Top")
		(29 "B.CrtYd" user "Package Geometry/Place Bound Bottom")
		(35 "F.Fab" user "Ref Des/Assembly Top")
		(33 "B.Fab" user "Ref Des/Assembly Bottom")
	)
	(footprint ""
		(layer "F.Cu")
		(at 179.999894 -3.800094)
		(property "Reference" "CN6"
			(at 0 0 0)
			(layer "F.SilkS")
			(hide yes)
			(effects
				(font
					(size 1.27 1.27)
				)
			)
		)
		(property "Value" "AMP-CONN76-8R-7-GP"
			(at -11.755374 -18.361152 0)
			(unlocked yes)
			(layer "F.Fab")
			(hide yes)
			(effects
				(font
					(size 1.016 1.016)
					(thickness 0.1524)
				)
			)
		)
		(property "Device Type" "PREFIT-76P-144260H400"
			(at -11.755374 -19.885152 0)
			(unlocked yes)
			(layer "F.Fab")
			(hide yes)
			(effects
				(font
					(size 1.016 1.016)
					(thickness 0.1524)
				)
			)
		)
		(duplicate_pad_numbers_are_jumpers no)
		(pad "A1" thru_hole circle
			(at 0 0)
			(size 0.762 0.762)
			(drill 0.359918)
			(layers "*.Cu" "*.Mask")
			(remove_unused_layers no)
			(net "PCIE_COMP_TO_SCC_0_DP")
			(clearance 0.1651)
			(thermal_gap 0.1651)
		)
		(pad "A2" thru_hole circle
			(at 1.800098 1.199896)
			(size 0.762 0.762)
			(drill 0.359918)
			(layers "*.Cu" "*.Mask")
			(remove_unused_layers no)
			(net "PCIE_COMP_TO_SCC_1_DP")
			(clearance 0.1651)
			(thermal_gap 0.1651)
		)
		(pad "A3" thru_hole circle
			(at 3.599942 0)
			(size 0.762 0.762)
			(drill 0.359918)
			(layers "*.Cu" "*.Mask")
			(remove_unused_layers no)
			(net "PCIE_COMP_TO_SCC_2_DP")
			(clearance 0.1651)
			(thermal_gap 0.1651)
		)
		(pad "A4" thru_hole circle
			(at 5.40004 1.199896)
			(size 0.762 0.762)
			(drill 0.359918)
			(layers "*.Cu" "*.Mask")
			(remove_unused_layers no)
			(net "PCIE_COMP_TO_SCC_3_DP")
			(clearance 0.1651)
			(thermal_gap 0.1651)
		)
		(pad "A5" thru_hole circle
			(at 7.199884 0)
			(size 0.762 0.762)
			(drill 0.359918)
			(layers "*.Cu" "*.Mask")
			(remove_unused_layers no)
			(net "PCIE_COMP_TO_SCC_4_DP")
			(clearance 0.1651)
			(thermal_gap 0.1651)
		)
		(pad "A6" thru_hole circle
			(at 8.999982 1.199896)
			(size 0.762 0.762)
			(drill 0.359918)
			(layers "*.Cu" "*.Mask")
			(remove_unused_layers no)
			(net "PCIE_COMP_TO_SCC_5_DP")
			(clearance 0.1651)
			(thermal_gap 0.1651)
		)
		(pad "A7" thru_hole circle
			(at 10.80008 0)
			(size 0.762 0.762)
			(drill 0.359918)
			(layers "*.Cu" "*.Mask")
			(remove_unused_layers no)
			(net "PCIE_COMP_TO_SCC_6_DP")
			(clearance 0.1651)
			(thermal_gap 0.1651)
		)
		(pad "A8" thru_hole circle
			(at 12.599924 1.199896)
			(size 0.762 0.762)
			(drill 0.359918)
			(layers "*.Cu" "*.Mask")
			(remove_unused_layers no)
			(net "PCIE_COMP_TO_SCC_7_DP")
			(clearance 0.1651)
			(thermal_gap 0.1651)
		)
		(pad "B1" thru_hole circle
			(at 0 -1.400048)
			(size 0.762 0.762)
			(drill 0.359918)
			(layers "*.Cu" "*.Mask")
			(remove_unused_layers no)
			(net "PCIE_COMP_TO_SCC_0_DN")
			(clearance 0.1651)
			(thermal_gap 0.1651)
		)
		(pad "B2" thru_hole circle
			(at 1.800098 -0.199898)
			(size 0.762 0.762)
			(drill 0.359918)
			(layers "*.Cu" "*.Mask")
			(remove_unused_layers no)
			(net "PCIE_COMP_TO_SCC_1_DN")
			(clearance 0.1651)
			(thermal_gap 0.1651)
		)
		(pad "B3" thru_hole circle
			(at 3.599942 -1.400048)
			(size 0.762 0.762)
			(drill 0.359918)
			(layers "*.Cu" "*.Mask")
			(remove_unused_layers no)
			(net "PCIE_COMP_TO_SCC_2_DN")
			(clearance 0.1651)
			(thermal_gap 0.1651)
		)
		(pad "B4" thru_hole circle
			(at 5.40004 -0.199898)
			(size 0.762 0.762)
			(drill 0.359918)
			(layers "*.Cu" "*.Mask")
			(remove_unused_layers no)
			(net "PCIE_COMP_TO_SCC_3_DN")
			(clearance 0.1651)
			(thermal_gap 0.1651)
		)
		(pad "B5" thru_hole circle
			(at 7.199884 -1.400048)
			(size 0.762 0.762)
			(drill 0.359918)
			(layers "*.Cu" "*.Mask")
			(remove_unused_layers no)
			(net "PCIE_COMP_TO_SCC_4_DN")
			(clearance 0.1651)
			(thermal_gap 0.1651)
		)
		(pad "B6" thru_hole circle
			(at 8.999982 -0.199898)
			(size 0.762 0.762)
			(drill 0.359918)
			(layers "*.Cu" "*.Mask")
			(remove_unused_layers no)
			(net "PCIE_COMP_TO_SCC_5_DN")
			(clearance 0.1651)
			(thermal_gap 0.1651)
		)
		(pad "B7" thru_hole circle
			(at 10.80008 -1.400048)
			(size 0.762 0.762)
			(drill 0.359918)
			(layers "*.Cu" "*.Mask")
			(remove_unused_layers no)
			(net "PCIE_COMP_TO_SCC_6_DN")
			(clearance 0.1651)
			(thermal_gap 0.1651)
		)
		(pad "B8" thru_hole circle
			(at 12.599924 -0.199898)
			(size 0.762 0.762)
			(drill 0.359918)
			(layers "*.Cu" "*.Mask")
			(remove_unused_layers no)
			(net "PCIE_COMP_TO_SCC_7_DN")
			(clearance 0.1651)
			(thermal_gap 0.1651)
		)
		(pad "C1" thru_hole circle
			(at 0 -3.599942)
			(size 0.762 0.762)
			(drill 0.359918)
			(layers "*.Cu" "*.Mask")
			(remove_unused_layers no)
			(net "PCIE_COMP_TO_SCC_CLK_0_DP")
			(clearance 0.1651)
			(thermal_gap 0.1651)
		)
		(pad "C2" thru_hole circle
			(at 1.800098 -2.400046)
			(size 0.762 0.762)
			(drill 0.359918)
			(layers "*.Cu" "*.Mask")
			(remove_unused_layers no)
			(net "I2C_BMC_RMT_SCL1")
			(clearance 0.1651)
			(thermal_gap 0.1651)
		)
		(pad "C3" thru_hole circle
			(at 3.599942 -3.599942)
			(size 0.762 0.762)
			(drill 0.359918)
			(layers "*.Cu" "*.Mask")
			(remove_unused_layers no)
			(net "I2C_SCC_SCL2")
			(clearance 0.1651)
			(thermal_gap 0.1651)
		)
		(pad "C4" thru_hole circle
			(at 5.40004 -2.400046)
			(size 0.762 0.762)
			(drill 0.359918)
			(layers "*.Cu" "*.Mask")
			(remove_unused_layers no)
			(net "COMP_SPARE_0")
			(clearance 0.1651)
			(thermal_gap 0.1651)
		)
		(pad "C5" thru_hole circle
			(at 7.199884 -3.599942)
			(size 0.762 0.762)
			(drill 0.359918)
			(layers "*.Cu" "*.Mask")
			(remove_unused_layers no)
			(net "UART_IOC_TX")
			(clearance 0.1651)
			(thermal_gap 0.1651)
		)
		(pad "C6" thru_hole circle
			(at 8.999982 -2.400046)
			(size 0.762 0.762)
			(drill 0.359918)
			(layers "*.Cu" "*.Mask")
			(remove_unused_layers no)
			(net "BMC_SPARE_0")
			(clearance 0.1651)
			(thermal_gap 0.1651)
		)
		(pad "C7" thru_hole circle
			(at 10.80008 -3.599942)
			(size 0.762 0.762)
			(drill 0.359918)
			(layers "*.Cu" "*.Mask")
			(remove_unused_layers no)
			(net "PCIE_COMP_TO_SCC_RST_0")
			(clearance 0.1651)
			(thermal_gap 0.1651)
		)
		(pad "C8" thru_hole circle
			(at 12.599924 -2.400046)
			(size 0.762 0.762)
			(drill 0.359918)
			(layers "*.Cu" "*.Mask")
			(remove_unused_layers no)
			(net "I2C_BMC_LOC_SCL0")
			(clearance 0.1651)
			(thermal_gap 0.1651)
		)
		(pad "D1" thru_hole circle
			(at 0 -4.99999)
			(size 0.762 0.762)
			(drill 0.359918)
			(layers "*.Cu" "*.Mask")
			(remove_unused_layers no)
			(net "PCIE_COMP_TO_SCC_CLK_0_DN")
			(clearance 0.1651)
			(thermal_gap 0.1651)
		)
		(pad "D2" thru_hole circle
			(at 1.800098 -3.800094)
			(size 0.762 0.762)
			(drill 0.359918)
			(layers "*.Cu" "*.Mask")
			(remove_unused_layers no)
			(net "I2C_BMC_RMT_SDA1")
			(clearance 0.1651)
			(thermal_gap 0.1651)
		)
		(pad "D3" thru_hole circle
			(at 3.599942 -4.99999)
			(size 0.762 0.762)
			(drill 0.359918)
			(layers "*.Cu" "*.Mask")
			(remove_unused_layers no)
			(net "I2C_SCC_SDA2")
			(clearance 0.1651)
			(thermal_gap 0.1651)
		)
		(pad "D4" thru_hole circle
			(at 5.40004 -3.800094)
			(size 0.762 0.762)
			(drill 0.359918)
			(layers "*.Cu" "*.Mask")
			(remove_unused_layers no)
			(net "Net_4")
			(clearance 0.1651)
			(thermal_gap 0.1651)
		)
		(pad "D5" thru_hole circle
			(at 7.199884 -4.99999)
			(size 0.762 0.762)
			(drill 0.359918)
			(layers "*.Cu" "*.Mask")
			(remove_unused_layers no)
			(net "UART_IOC_RX")
			(clearance 0.1651)
			(thermal_gap 0.1651)
		)
		(pad "D6" thru_hole circle
			(at 8.999982 -3.800094)
			(size 0.762 0.762)
			(drill 0.359918)
			(layers "*.Cu" "*.Mask")
			(remove_unused_layers no)
			(net "BMC_SPARE_1")
			(clearance 0.1651)
			(thermal_gap 0.1651)
		)
		(pad "D7" thru_hole circle
			(at 10.80008 -4.99999)
			(size 0.762 0.762)
			(drill 0.359918)
			(layers "*.Cu" "*.Mask")
			(remove_unused_layers no)
			(net "BMC_RMT_HEARTBEAT")
			(clearance 0.1651)
			(thermal_gap 0.1651)
		)
		(pad "D8" thru_hole circle
			(at 12.599924 -3.800094)
			(size 0.762 0.762)
			(drill 0.359918)
			(layers "*.Cu" "*.Mask")
			(remove_unused_layers no)
			(net "I2C_BMC_LOC_SDA0")
			(clearance 0.1651)
			(thermal_gap 0.1651)
		)
		(pad "E1" thru_hole circle
			(at 0 -7.199884)
			(size 0.762 0.762)
			(drill 0.359918)
			(layers "*.Cu" "*.Mask")
			(remove_unused_layers no)
			(net "PCIE_SCC_TO_COMP_0_DP")
			(clearance 0.1651)
			(thermal_gap 0.1651)
		)
		(pad "E2" thru_hole circle
			(at 1.800098 -5.999988)
			(size 0.762 0.762)
			(drill 0.359918)
			(layers "*.Cu" "*.Mask")
			(remove_unused_layers no)
			(net "PCIE_SCC_TO_COMP_1_DP")
			(clearance 0.1651)
			(thermal_gap 0.1651)
		)
		(pad "E3" thru_hole circle
			(at 3.599942 -7.199884)
			(size 0.762 0.762)
			(drill 0.359918)
			(layers "*.Cu" "*.Mask")
			(remove_unused_layers no)
			(net "PCIE_SCC_TO_COMP_2_DP")
			(clearance 0.1651)
			(thermal_gap 0.1651)
		)
		(pad "E4" thru_hole circle
			(at 5.40004 -5.999988)
			(size 0.762 0.762)
			(drill 0.359918)
			(layers "*.Cu" "*.Mask")
			(remove_unused_layers no)
			(net "PCIE_SCC_TO_COMP_3_DP")
			(clearance 0.1651)
			(thermal_gap 0.1651)
		)
		(pad "E5" thru_hole circle
			(at 7.199884 -7.199884)
			(size 0.762 0.762)
			(drill 0.359918)
			(layers "*.Cu" "*.Mask")
			(remove_unused_layers no)
			(net "PCIE_SCC_TO_COMP_4_DP")
			(clearance 0.1651)
			(thermal_gap 0.1651)
		)
		(pad "E6" thru_hole circle
			(at 8.999982 -5.999988)
			(size 0.762 0.762)
			(drill 0.359918)
			(layers "*.Cu" "*.Mask")
			(remove_unused_layers no)
			(net "PCIE_SCC_TO_COMP_5_DP")
			(clearance 0.1651)
			(thermal_gap 0.1651)
		)
		(pad "E7" thru_hole circle
			(at 10.80008 -7.199884)
			(size 0.762 0.762)
			(drill 0.359918)
			(layers "*.Cu" "*.Mask")
			(remove_unused_layers no)
			(net "PCIE_SCC_TO_COMP_6_DP")
			(clearance 0.1651)
			(thermal_gap 0.1651)
		)
		(pad "E8" thru_hole circle
			(at 12.599924 -5.999988)
			(size 0.762 0.762)
			(drill 0.359918)
			(layers "*.Cu" "*.Mask")
			(remove_unused_layers no)
			(net "PCIE_SCC_TO_COMP_7_DP")
			(clearance 0.1651)
			(thermal_gap 0.1651)
		)
		(pad "F1" thru_hole circle
			(at 0 -8.599932)
			(size 0.762 0.762)
			(drill 0.359918)
			(layers "*.Cu" "*.Mask")
			(remove_unused_layers no)
			(net "PCIE_SCC_TO_COMP_0_DN")
			(clearance 0.1651)
			(thermal_gap 0.1651)
		)
		(pad "F2" thru_hole circle
			(at 1.800098 -7.400036)
			(size 0.762 0.762)
			(drill 0.359918)
			(layers "*.Cu" "*.Mask")
			(remove_unused_layers no)
			(net "PCIE_SCC_TO_COMP_1_DN")
			(clearance 0.1651)
			(thermal_gap 0.1651)
		)
		(pad "F3" thru_hole circle
			(at 3.599942 -8.599932)
			(size 0.762 0.762)
			(drill 0.359918)
			(layers "*.Cu" "*.Mask")
			(remove_unused_layers no)
			(net "PCIE_SCC_TO_COMP_2_DN")
			(clearance 0.1651)
			(thermal_gap 0.1651)
		)
		(pad "F4" thru_hole circle
			(at 5.40004 -7.400036)
			(size 0.762 0.762)
			(drill 0.359918)
			(layers "*.Cu" "*.Mask")
			(remove_unused_layers no)
			(net "PCIE_SCC_TO_COMP_3_DN")
			(clearance 0.1651)
			(thermal_gap 0.1651)
		)
		(pad "F5" thru_hole circle
			(at 7.199884 -8.599932)
			(size 0.762 0.762)
			(drill 0.359918)
			(layers "*.Cu" "*.Mask")
			(remove_unused_layers no)
			(net "PCIE_SCC_TO_COMP_4_DN")
			(clearance 0.1651)
			(thermal_gap 0.1651)
		)
		(pad "F6" thru_hole circle
			(at 8.999982 -7.400036)
			(size 0.762 0.762)
			(drill 0.359918)
			(layers "*.Cu" "*.Mask")
			(remove_unused_layers no)
			(net "PCIE_SCC_TO_COMP_5_DN")
			(clearance 0.1651)
			(thermal_gap 0.1651)
		)
		(pad "F7" thru_hole circle
			(at 10.80008 -8.599932)
			(size 0.762 0.762)
			(drill 0.359918)
			(layers "*.Cu" "*.Mask")
			(remove_unused_layers no)
			(net "PCIE_SCC_TO_COMP_6_DN")
			(clearance 0.1651)
			(thermal_gap 0.1651)
		)
		(pad "F8" thru_hole circle
			(at 12.599924 -7.400036)
			(size 0.762 0.762)
			(drill 0.359918)
			(layers "*.Cu" "*.Mask")
			(remove_unused_layers no)
			(net "PCIE_SCC_TO_COMP_7_DN")
			(clearance 0.1651)
			(thermal_gap 0.1651)
		)
		(pad "GND1" thru_hole circle
			(at 0 -2.500122)
			(size 0.762 0.762)
			(drill 0.359918)
			(layers "*.Cu" "*.Mask")
			(remove_unused_layers no)
			(net "GND")
			(clearance 0.1651)
			(thermal_gap 0.1651)
		)
		(pad "GND2" thru_hole circle
			(at 0 -6.100064)
			(size 0.762 0.762)
			(drill 0.359918)
			(layers "*.Cu" "*.Mask")
			(remove_unused_layers no)
			(net "GND")
			(clearance 0.1651)
			(thermal_gap 0.1651)
		)
		(pad "GND3" thru_hole circle
			(at 0 -9.700006)
			(size 0.762 0.762)
			(drill 0.359918)
			(layers "*.Cu" "*.Mask")
			(remove_unused_layers no)
			(net "GND")
			(clearance 0.1651)
			(thermal_gap 0.1651)
		)
		(pad "GND4" thru_hole circle
			(at 1.800098 2.29997)
			(size 0.762 0.762)
			(drill 0.359918)
			(layers "*.Cu" "*.Mask")
			(remove_unused_layers no)
			(net "GND")
			(clearance 0.1651)
			(thermal_gap 0.1651)
		)
		(pad "GND5" thru_hole circle
			(at 1.800098 -1.299972)
			(size 0.762 0.762)
			(drill 0.359918)
			(layers "*.Cu" "*.Mask")
			(remove_unused_layers no)
			(net "GND")
			(clearance 0.1651)
			(thermal_gap 0.1651)
		)
		(pad "GND6" thru_hole circle
			(at 1.800098 -4.899914)
			(size 0.762 0.762)
			(drill 0.359918)
			(layers "*.Cu" "*.Mask")
			(remove_unused_layers no)
			(net "GND")
			(clearance 0.1651)
			(thermal_gap 0.1651)
		)
		(pad "GND7" thru_hole circle
			(at 1.800098 -8.50011)
			(size 0.762 0.762)
			(drill 0.359918)
			(layers "*.Cu" "*.Mask")
			(remove_unused_layers no)
			(net "GND")
			(clearance 0.1651)
			(thermal_gap 0.1651)
		)
		(pad "GND8" thru_hole circle
			(at 3.599942 -2.500122)
			(size 0.762 0.762)
			(drill 0.359918)
			(layers "*.Cu" "*.Mask")
			(remove_unused_layers no)
			(net "GND")
			(clearance 0.1651)
			(thermal_gap 0.1651)
		)
		(pad "GND9" thru_hole circle
			(at 3.599942 -6.100064)
			(size 0.762 0.762)
			(drill 0.359918)
			(layers "*.Cu" "*.Mask")
			(remove_unused_layers no)
			(net "GND")
			(clearance 0.1651)
			(thermal_gap 0.1651)
		)
		(pad "GND10" thru_hole circle
			(at 3.599942 -9.700006)
			(size 0.762 0.762)
			(drill 0.359918)
			(layers "*.Cu" "*.Mask")
			(remove_unused_layers no)
			(net "GND")
			(clearance 0.1651)
			(thermal_gap 0.1651)
		)
		(pad "GND11" thru_hole circle
			(at 5.40004 2.29997)
			(size 0.762 0.762)
			(drill 0.359918)
			(layers "*.Cu" "*.Mask")
			(remove_unused_layers no)
			(net "GND")
			(clearance 0.1651)
			(thermal_gap 0.1651)
		)
		(pad "GND12" thru_hole circle
			(at 5.40004 -1.299972)
			(size 0.762 0.762)
			(drill 0.359918)
			(layers "*.Cu" "*.Mask")
			(remove_unused_layers no)
			(net "GND")
			(clearance 0.1651)
			(thermal_gap 0.1651)
		)
		(pad "GND13" thru_hole circle
			(at 5.40004 -4.899914)
			(size 0.762 0.762)
			(drill 0.359918)
			(layers "*.Cu" "*.Mask")
			(remove_unused_layers no)
			(net "GND")
			(clearance 0.1651)
			(thermal_gap 0.1651)
		)
		(pad "GND14" thru_hole circle
			(at 5.40004 -8.50011)
			(size 0.762 0.762)
			(drill 0.359918)
			(layers "*.Cu" "*.Mask")
			(remove_unused_layers no)
			(net "GND")
			(clearance 0.1651)
			(thermal_gap 0.1651)
		)
		(pad "GND15" thru_hole circle
			(at 7.199884 -2.500122)
			(size 0.762 0.762)
			(drill 0.359918)
			(layers "*.Cu" "*.Mask")
			(remove_unused_layers no)
			(net "GND")
			(clearance 0.1651)
			(thermal_gap 0.1651)
		)
		(pad "GND16" thru_hole circle
			(at 7.199884 -6.100064)
			(size 0.762 0.762)
			(drill 0.359918)
			(layers "*.Cu" "*.Mask")
			(remove_unused_layers no)
			(net "GND")
			(clearance 0.1651)
			(thermal_gap 0.1651)
		)
		(pad "GND17" thru_hole circle
			(at 7.199884 -9.700006)
			(size 0.762 0.762)
			(drill 0.359918)
			(layers "*.Cu" "*.Mask")
			(remove_unused_layers no)
			(net "GND")
			(clearance 0.1651)
			(thermal_gap 0.1651)
		)
		(pad "GND18" thru_hole circle
			(at 8.999982 2.29997)
			(size 0.762 0.762)
			(drill 0.359918)
			(layers "*.Cu" "*.Mask")
			(remove_unused_layers no)
			(net "GND")
			(clearance 0.1651)
			(thermal_gap 0.1651)
		)
		(pad "GND19" thru_hole circle
			(at 8.999982 -1.299972)
			(size 0.762 0.762)
			(drill 0.359918)
			(layers "*.Cu" "*.Mask")
			(remove_unused_layers no)
			(net "GND")
			(clearance 0.1651)
			(thermal_gap 0.1651)
		)
		(pad "GND20" thru_hole circle
			(at 8.999982 -4.899914)
			(size 0.762 0.762)
			(drill 0.359918)
			(layers "*.Cu" "*.Mask")
			(remove_unused_layers no)
			(net "GND")
			(clearance 0.1651)
			(thermal_gap 0.1651)
		)
		(pad "GND21" thru_hole circle
			(at 8.999982 -8.50011)
			(size 0.762 0.762)
			(drill 0.359918)
			(layers "*.Cu" "*.Mask")
			(remove_unused_layers no)
			(net "GND")
			(clearance 0.1651)
			(thermal_gap 0.1651)
		)
		(pad "GND22" thru_hole circle
			(at 10.80008 -2.500122)
			(size 0.762 0.762)
			(drill 0.359918)
			(layers "*.Cu" "*.Mask")
			(remove_unused_layers no)
			(net "GND")
			(clearance 0.1651)
			(thermal_gap 0.1651)
		)
		(pad "GND23" thru_hole circle
			(at 10.80008 -6.100064)
			(size 0.762 0.762)
			(drill 0.359918)
			(layers "*.Cu" "*.Mask")
			(remove_unused_layers no)
			(net "GND")
			(clearance 0.1651)
			(thermal_gap 0.1651)
		)
		(pad "GND24" thru_hole circle
			(at 10.80008 -9.700006)
			(size 0.762 0.762)
			(drill 0.359918)
			(layers "*.Cu" "*.Mask")
			(remove_unused_layers no)
			(net "GND")
			(clearance 0.1651)
			(thermal_gap 0.1651)
		)
		(pad "GND25" thru_hole circle
			(at 12.599924 2.29997)
			(size 0.762 0.762)
			(drill 0.359918)
			(layers "*.Cu" "*.Mask")
			(remove_unused_layers no)
			(net "GND")
			(clearance 0.1651)
			(thermal_gap 0.1651)
		)
		(pad "GND26" thru_hole circle
			(at 12.599924 -1.299972)
			(size 0.762 0.762)
			(drill 0.359918)
			(layers "*.Cu" "*.Mask")
			(remove_unused_layers no)
			(net "GND")
			(clearance 0.1651)
			(thermal_gap 0.1651)
		)
		(pad "GND27" thru_hole circle
			(at 12.599924 -4.899914)
			(size 0.762 0.762)
			(drill 0.359918)
			(layers "*.Cu" "*.Mask")
			(remove_unused_layers no)
			(net "GND")
			(clearance 0.1651)
			(thermal_gap 0.1651)
		)
	)
)
